(kicad_pcb
	(version 20260206)
	(generator "pcbnew")
	(generator_version "10.0")
	(general
		(thickness 1.6)
		(legacy_teardrops no)
	)
	(paper "A4")
	(title_block
		(title "Wiwynn_Tioga_Pass_MB.brd")
		(comment 1 "Tioga Pass / footprints 2483-2490 of 4770")
	)
	(layers
		(0 "F.Cu" signal "TOP")
		(4 "In1.Cu" signal "L2GND")
		(6 "In2.Cu" signal "L3")
		(8 "In3.Cu" signal "L4GND")
		(10 "In4.Cu" signal "L5")
		(12 "In5.Cu" signal "L6GND")
		(14 "In6.Cu" signal "L7VCC")
		(16 "In7.Cu" signal "L8VCC")
		(18 "In8.Cu" signal "L9GND")
		(20 "In9.Cu" signal "L10")
		(22 "In10.Cu" signal "L11GND")
		(24 "In11.Cu" signal "L12")
		(26 "In12.Cu" signal "L13GND")
		(2 "B.Cu" signal "BOTTOM")
		(9 "F.Adhes" user "F.Adhesive")
		(11 "B.Adhes" user "B.Adhesive")
		(13 "F.Paste" user "Package Geometry/Pastemask Top")
		(15 "B.Paste" user "Package Geometry/Pastemask Bottom")
		(5 "F.SilkS" user "Ref Des/Silkscreen Top")
		(7 "B.SilkS" user "Ref Des/Silkscreen Bottom")
		(1 "F.Mask" user "Board Geometry/Soldermask Top")
		(3 "B.Mask" user "Board Geometry/Soldermask Bottom")
		(17 "Dwgs.User" user "User.Drawings")
		(19 "Cmts.User" user "User.Comments")
		(21 "Eco1.User" user "User.Eco1")
		(23 "Eco2.User" user "User.Eco2")
		(25 "Edge.Cuts" user "Board Geometry/Outline")
		(27 "Margin" user)
		(31 "F.CrtYd" user "Package Geometry/Place Bound Top")
		(29 "B.CrtYd" user "Package Geometry/Place Bound Bottom")
		(35 "F.Fab" user "Ref Des/Assembly Top")
		(33 "B.Fab" user "Ref Des/Assembly Bottom")
	)
	(footprint ""
		(layer "B.Cu")
		(at 450.5325 -26.543 -90)
		(property "Reference" "C6W3"
			(at 0.8382 -0.67818 270)
			(unlocked yes)
			(layer "B.SilkS")
			(effects
				(font
					(size 0.4064 0.254)
					(thickness 0.1524)
				)
				(justify left mirror)
			)
		)
		(property "Value" ""
			(at 0 0 90)
			(layer "B.Fab")
			(effects
				(font
					(size 1.27 1.27)
				)
				(justify mirror)
			)
		)
		(duplicate_pad_numbers_are_jumpers no)
		(fp_poly
			(pts
				(xy -0.3048 -0.1016) (xy -0.3048 0.9906) (xy 0.3048 0.9906) (xy 0.3048 -0.1016)
			)
			(stroke
				(width 0)
				(type default)
			)
			(fill no)
			(layer "B.CrtYd")
		)
		(fp_line
			(start -0.3048 0.9906)
			(end -0.3048 -0.1016)
			(stroke
				(width 0.1)
				(type default)
			)
			(layer "B.Fab")
		)
		(fp_line
			(start 0.3048 0.9906)
			(end -0.3048 0.9906)
			(stroke
				(width 0.1)
				(type default)
			)
			(layer "B.Fab")
		)
		(fp_line
			(start -0.3048 -0.1016)
			(end 0.3048 -0.1016)
			(stroke
				(width 0.1)
				(type default)
			)
			(layer "B.Fab")
		)
		(fp_line
			(start 0.3048 -0.1016)
			(end 0.3048 0.9906)
			(stroke
				(width 0.1)
				(type default)
			)
			(layer "B.Fab")
		)
		(pad "1" smd rect
			(at 0 0 90)
			(size 0.508 0.508)
			(layers "B.Cu" "B.Mask" "B.Paste")
			(net "P3V3_STBY")
		)
		(pad "2" smd rect
			(at 0 0.889 90)
			(size 0.508 0.508)
			(layers "B.Cu" "B.Mask" "B.Paste")
			(net "GND")
		)
		(zone
			(layer "B.Cu")
			(hatch none 0.5)
			(connect_pads
				(clearance 0)
			)
			(min_thickness 0.25)
			(keepout
				(tracks not_allowed)
				(vias allowed)
				(pads allowed)
				(copperpour not_allowed)
				(footprints allowed)
			)
			(placement
				(enabled no)
				(sheetname "")
			)
			(fill
				(thermal_gap 0.5)
				(thermal_bridge_width 0.5)
				(island_removal_mode 0)
			)
			(polygon
				(pts
					(xy 449.8975 -26.289) (xy 449.8975 -26.797) (xy 450.2785 -26.797) (xy 450.2785 -26.289)
				)
			)
		)
		(zone
			(layer "B.Cu")
			(hatch none 0.5)
			(connect_pads
				(clearance 0)
			)
			(min_thickness 0.25)
			(keepout
				(tracks allowed)
				(vias not_allowed)
				(pads allowed)
				(copperpour not_allowed)
				(footprints allowed)
			)
			(placement
				(enabled no)
				(sheetname "")
			)
			(fill
				(thermal_gap 0.5)
				(thermal_bridge_width 0.5)
				(island_removal_mode 0)
			)
			(polygon
				(pts
					(xy 450.2785 -26.289) (xy 450.2785 -26.797) (xy 449.8975 -26.797) (xy 449.8975 -26.289)
				)
			)
		)
	)
	(footprint ""
		(layer "B.Cu")
		(at 408.1526 -154.4828 90)
		(property "Reference" "C2L5"
			(at 0 0 90)
			(layer "B.SilkS")
			(hide yes)
			(effects
				(font
					(size 1.27 1.27)
				)
				(justify mirror)
			)
		)
		(property "Value" ""
			(at 0 0 90)
			(layer "B.Fab")
			(effects
				(font
					(size 1.27 1.27)
				)
				(justify mirror)
			)
		)
		(duplicate_pad_numbers_are_jumpers no)
		(fp_poly
			(pts
				(xy -0.3048 -0.1016) (xy -0.3048 0.9906) (xy 0.3048 0.9906) (xy 0.3048 -0.1016)
			)
			(stroke
				(width 0)
				(type default)
			)
			(fill no)
			(layer "B.CrtYd")
		)
		(fp_line
			(start 0.3048 -0.1016)
			(end 0.3048 0.9906)
			(stroke
				(width 0.1)
				(type default)
			)
			(layer "B.Fab")
		)
		(fp_line
			(start -0.3048 -0.1016)
			(end 0.3048 -0.1016)
			(stroke
				(width 0.1)
				(type default)
			)
			(layer "B.Fab")
		)
		(fp_line
			(start 0.3048 0.9906)
			(end -0.3048 0.9906)
			(stroke
				(width 0.1)
				(type default)
			)
			(layer "B.Fab")
		)
		(fp_line
			(start -0.3048 0.9906)
			(end -0.3048 -0.1016)
			(stroke
				(width 0.1)
				(type default)
			)
			(layer "B.Fab")
		)
		(pad "1" smd rect
			(at 0 0 270)
			(size 0.508 0.508)
			(layers "B.Cu" "B.Mask" "B.Paste")
			(net "SATA6G_PCH_PCIE_UP_SATA_RXN<7>")
		)
		(pad "2" smd rect
			(at 0 0.889 270)
			(size 0.508 0.508)
			(layers "B.Cu" "B.Mask" "B.Paste")
			(net "SATA6G_P7_RX_C_DN")
		)
		(zone
			(layer "B.Cu")
			(hatch none 0.5)
			(connect_pads
				(clearance 0)
			)
			(min_thickness 0.25)
			(keepout
				(tracks allowed)
				(vias not_allowed)
				(pads allowed)
				(copperpour not_allowed)
				(footprints allowed)
			)
			(placement
				(enabled no)
				(sheetname "")
			)
			(fill
				(thermal_gap 0.5)
				(thermal_bridge_width 0.5)
				(island_removal_mode 0)
			)
			(polygon
				(pts
					(xy 408.4066 -154.7368) (xy 408.4066 -154.2288) (xy 408.7876 -154.2288) (xy 408.7876 -154.7368)
				)
			)
		)
		(zone
			(layer "B.Cu")
			(hatch none 0.5)
			(connect_pads
				(clearance 0)
			)
			(min_thickness 0.25)
			(keepout
				(tracks not_allowed)
				(vias allowed)
				(pads allowed)
				(copperpour not_allowed)
				(footprints allowed)
			)
			(placement
				(enabled no)
				(sheetname "")
			)
			(fill
				(thermal_gap 0.5)
				(thermal_bridge_width 0.5)
				(island_removal_mode 0)
			)
			(polygon
				(pts
					(xy 408.7876 -154.7368) (xy 408.7876 -154.2288) (xy 408.4066 -154.2288) (xy 408.4066 -154.7368)
				)
			)
		)
	)
	(footprint ""
		(layer "B.Cu")
		(at 379.3363 -67.21856)
		(property "Reference" "R7E18"
			(at 0 0 0)
			(layer "B.SilkS")
			(hide yes)
			(effects
				(font
					(size 1.27 1.27)
				)
				(justify mirror)
			)
		)
		(property "Value" ""
			(at 0 0 0)
			(layer "B.Fab")
			(effects
				(font
					(size 1.27 1.27)
				)
				(justify mirror)
			)
		)
		(duplicate_pad_numbers_are_jumpers no)
		(fp_poly
			(pts
				(xy 0.2794 -0.1016) (xy -0.2794 -0.1016) (xy -0.2794 0.9906) (xy 0.2794 0.9906)
			)
			(stroke
				(width 0)
				(type default)
			)
			(fill no)
			(layer "B.CrtYd")
		)
		(fp_line
			(start -0.2794 -0.1016)
			(end 0.2794 -0.1016)
			(stroke
				(width 0.1)
				(type default)
			)
			(layer "B.Fab")
		)
		(fp_line
			(start -0.2794 0.9906)
			(end -0.2794 -0.1016)
			(stroke
				(width 0.1)
				(type default)
			)
			(layer "B.Fab")
		)
		(fp_line
			(start 0.2794 -0.1016)
			(end 0.2794 0.9906)
			(stroke
				(width 0.1)
				(type default)
			)
			(layer "B.Fab")
		)
		(fp_line
			(start 0.2794 0.9906)
			(end -0.2794 0.9906)
			(stroke
				(width 0.1)
				(type default)
			)
			(layer "B.Fab")
		)
		(pad "1" smd rect
			(at 0 0 180)
			(size 0.508 0.508)
			(layers "B.Cu" "B.Mask" "B.Paste")
			(net "P3V3_STBY")
		)
		(pad "2" smd rect
			(at 0 0.889 180)
			(size 0.508 0.508)
			(layers "B.Cu" "B.Mask" "B.Paste")
			(net "RST_RSMRST_N")
		)
		(zone
			(layer "B.Cu")
			(hatch none 0.5)
			(connect_pads
				(clearance 0)
			)
			(min_thickness 0.25)
			(keepout
				(tracks allowed)
				(vias not_allowed)
				(pads allowed)
				(copperpour not_allowed)
				(footprints allowed)
			)
			(placement
				(enabled no)
				(sheetname "")
			)
			(fill
				(thermal_gap 0.5)
				(thermal_bridge_width 0.5)
				(island_removal_mode 0)
			)
			(polygon
				(pts
					(xy 379.5903 -66.96456) (xy 379.0823 -66.96456) (xy 379.0823 -66.58356) (xy 379.5903 -66.58356)
				)
			)
		)
		(zone
			(layer "B.Cu")
			(hatch none 0.5)
			(connect_pads
				(clearance 0)
			)
			(min_thickness 0.25)
			(keepout
				(tracks not_allowed)
				(vias allowed)
				(pads allowed)
				(copperpour not_allowed)
				(footprints allowed)
			)
			(placement
				(enabled no)
				(sheetname "")
			)
			(fill
				(thermal_gap 0.5)
				(thermal_bridge_width 0.5)
				(island_removal_mode 0)
			)
			(polygon
				(pts
					(xy 379.5903 -66.58356) (xy 379.0823 -66.58356) (xy 379.0823 -66.96456) (xy 379.5903 -66.96456)
				)
			)
		)
	)
	(footprint ""
		(layer "B.Cu")
		(at 259.6896 -3.321812 90)
		(property "Reference" "C5G21"
			(at -1.64973 0.78994 180)
			(unlocked yes)
			(layer "B.SilkS")
			(effects
				(font
					(size 0.7874 0.5842)
					(thickness 0.1524)
				)
				(justify mirror)
			)
		)
		(property "Value" ""
			(at 0 0 90)
			(layer "B.Fab")
			(effects
				(font
					(size 1.27 1.27)
				)
				(justify mirror)
			)
		)
		(duplicate_pad_numbers_are_jumpers no)
		(fp_rect
			(start -0.7239 -0.2159)
			(end 0.7239 1.9939)
			(stroke
				(width 0)
				(type default)
			)
			(fill no)
			(layer "B.CrtYd")
		)
		(fp_line
			(start 0.7239 -0.2159)
			(end 0.7239 1.9939)
			(stroke
				(width 0.1)
				(type default)
			)
			(layer "B.Fab")
		)
		(fp_line
			(start -0.7239 -0.2159)
			(end 0.7239 -0.2159)
			(stroke
				(width 0.1)
				(type default)
			)
			(layer "B.Fab")
		)
		(fp_line
			(start 0.7239 1.9939)
			(end -0.7239 1.9939)
			(stroke
				(width 0.1)
				(type default)
			)
			(layer "B.Fab")
		)
		(fp_line
			(start -0.7239 1.9939)
			(end -0.7239 -0.2159)
			(stroke
				(width 0.1)
				(type default)
			)
			(layer "B.Fab")
		)
		(pad "1" smd rect
			(at 0 0 270)
			(size 1.27 1.016)
			(layers "B.Cu" "B.Mask" "B.Paste")
			(net "PVDDQ_ABC")
		)
		(pad "2" smd rect
			(at 0 1.778 270)
			(size 1.27 1.016)
			(layers "B.Cu" "B.Mask" "B.Paste")
			(net "GND")
		)
		(zone
			(layer "B.Cu")
			(hatch none 0.5)
			(connect_pads
				(clearance 0)
			)
			(min_thickness 0.25)
			(keepout
				(tracks not_allowed)
				(vias allowed)
				(pads allowed)
				(copperpour not_allowed)
				(footprints allowed)
			)
			(placement
				(enabled no)
				(sheetname "")
			)
			(fill
				(thermal_gap 0.5)
				(thermal_bridge_width 0.5)
				(island_removal_mode 0)
			)
			(polygon
				(pts
					(xy 260.1976 -2.686812) (xy 260.9596 -2.686812) (xy 260.9596 -3.956812) (xy 260.1976 -3.956812)
				)
			)
		)
	)
	(footprint ""
		(layer "B.Cu")
		(at 479.923602 -58.010298 90)
		(property "Reference" "R8E21"
			(at 0 0 90)
			(layer "B.SilkS")
			(hide yes)
			(effects
				(font
					(size 1.27 1.27)
				)
				(justify mirror)
			)
		)
		(property "Value" ""
			(at 0 0 90)
			(layer "B.Fab")
			(effects
				(font
					(size 1.27 1.27)
				)
				(justify mirror)
			)
		)
		(duplicate_pad_numbers_are_jumpers no)
		(fp_poly
			(pts
				(xy 0.2794 -0.1016) (xy -0.2794 -0.1016) (xy -0.2794 0.9906) (xy 0.2794 0.9906)
			)
			(stroke
				(width 0)
				(type default)
			)
			(fill no)
			(layer "B.CrtYd")
		)
		(fp_line
			(start 0.2794 -0.1016)
			(end 0.2794 0.9906)
			(stroke
				(width 0.1)
				(type default)
			)
			(layer "B.Fab")
		)
		(fp_line
			(start -0.2794 -0.1016)
			(end 0.2794 -0.1016)
			(stroke
				(width 0.1)
				(type default)
			)
			(layer "B.Fab")
		)
		(fp_line
			(start 0.2794 0.9906)
			(end -0.2794 0.9906)
			(stroke
				(width 0.1)
				(type default)
			)
			(layer "B.Fab")
		)
		(fp_line
			(start -0.2794 0.9906)
			(end -0.2794 -0.1016)
			(stroke
				(width 0.1)
				(type default)
			)
			(layer "B.Fab")
		)
		(pad "1" smd rect
			(at 0 0 270)
			(size 0.508 0.508)
			(layers "B.Cu" "B.Mask" "B.Paste")
			(net "FM_PE_SPRV_WAKE_N")
		)
		(pad "2" smd rect
			(at 0 0.889 270)
			(size 0.508 0.508)
			(layers "B.Cu" "B.Mask" "B.Paste")
			(net "FM_ALL_WAKE_N")
		)
		(zone
			(layer "B.Cu")
			(hatch none 0.5)
			(connect_pads
				(clearance 0)
			)
			(min_thickness 0.25)
			(keepout
				(tracks allowed)
				(vias not_allowed)
				(pads allowed)
				(copperpour not_allowed)
				(footprints allowed)
			)
			(placement
				(enabled no)
				(sheetname "")
			)
			(fill
				(thermal_gap 0.5)
				(thermal_bridge_width 0.5)
				(island_removal_mode 0)
			)
			(polygon
				(pts
					(xy 480.177602 -58.264298) (xy 480.177602 -57.756298) (xy 480.558602 -57.756298) (xy 480.558602 -58.264298)
				)
			)
		)
		(zone
			(layer "B.Cu")
			(hatch none 0.5)
			(connect_pads
				(clearance 0)
			)
			(min_thickness 0.25)
			(keepout
				(tracks not_allowed)
				(vias allowed)
				(pads allowed)
				(copperpour not_allowed)
				(footprints allowed)
			)
			(placement
				(enabled no)
				(sheetname "")
			)
			(fill
				(thermal_gap 0.5)
				(thermal_bridge_width 0.5)
				(island_removal_mode 0)
			)
			(polygon
				(pts
					(xy 480.558602 -58.264298) (xy 480.558602 -57.756298) (xy 480.177602 -57.756298) (xy 480.177602 -58.264298)
				)
			)
		)
	)
	(footprint ""
		(layer "B.Cu")
		(at 385.9276 -65.3288 90)
		(property "Reference" "Q8F1"
			(at -3.42773 -1.1938 180)
			(unlocked yes)
			(layer "B.SilkS")
			(effects
				(font
					(size 0.7874 0.5842)
					(thickness 0.1524)
				)
				(justify left mirror)
			)
		)
		(property "Value" ""
			(at 0 0 90)
			(layer "B.Fab")
			(effects
				(font
					(size 1.27 1.27)
				)
				(justify mirror)
			)
		)
		(duplicate_pad_numbers_are_jumpers no)
		(fp_line
			(start -0.9525 -0.5715)
			(end -1.778 -0.5715)
			(stroke
				(width 0.1524)
				(type default)
			)
			(layer "B.SilkS")
		)
		(fp_line
			(start -1.778 -0.5715)
			(end -1.778 0.3175)
			(stroke
				(width 0.1524)
				(type default)
			)
			(layer "B.SilkS")
		)
		(fp_line
			(start -0.381 0.635)
			(end -0.381 1.27)
			(stroke
				(width 0.1524)
				(type default)
			)
			(layer "B.SilkS")
		)
		(fp_line
			(start -0.9525 2.4765)
			(end -1.778 2.4765)
			(stroke
				(width 0.1524)
				(type default)
			)
			(layer "B.SilkS")
		)
		(fp_line
			(start -1.778 2.4765)
			(end -1.778 1.5875)
			(stroke
				(width 0.1524)
				(type default)
			)
			(layer "B.SilkS")
		)
		(fp_circle
			(center 0.9525 -0.9271)
			(end 0.9525 -0.8001)
			(stroke
				(width 0.254)
				(type default)
			)
			(fill no)
			(layer "B.SilkS")
		)
		(fp_poly
			(pts
				(xy -1.778 2.4765) (xy -0.381 2.4765) (xy -0.381 -0.5715) (xy -1.778 -0.5715)
			)
			(stroke
				(width 0)
				(type default)
			)
			(fill no)
			(layer "B.CrtYd")
		)
		(fp_line
			(start -0.381 -0.5715)
			(end -0.381 2.4765)
			(stroke
				(width 0.1)
				(type default)
			)
			(layer "B.Fab")
		)
		(fp_line
			(start -1.778 -0.5715)
			(end -0.381 -0.5715)
			(stroke
				(width 0.1)
				(type default)
			)
			(layer "B.Fab")
		)
		(fp_line
			(start -0.381 2.4765)
			(end -1.778 2.4765)
			(stroke
				(width 0.1)
				(type default)
			)
			(layer "B.Fab")
		)
		(fp_line
			(start -1.778 2.4765)
			(end -1.778 -0.5715)
			(stroke
				(width 0.1)
				(type default)
			)
			(layer "B.Fab")
		)
		(fp_circle
			(center 0.9525 -0.9271)
			(end 0.9525 -0.8001)
			(stroke
				(width 0.254)
				(type default)
			)
			(fill no)
			(layer "B.Fab")
		)
		(pad "1" smd rect
			(at 0 0 270)
			(size 1.143 0.508)
			(layers "B.Cu" "B.Mask" "B.Paste")
			(net "FM_BACKUP_BIOS_SEL_N")
		)
		(pad "2" smd rect
			(at 0 1.905 270)
			(size 1.143 0.508)
			(layers "B.Cu" "B.Mask" "B.Paste")
			(net "GND")
		)
		(pad "3" smd rect
			(at -2.159 0.9525 270)
			(size 1.143 0.508)
			(layers "B.Cu" "B.Mask" "B.Paste")
			(net "FM_DUAL_BIOS_SEL_N")
		)
	)
	(footprint ""
		(layer "B.Cu")
		(at 169.926 -87.757)
		(property "Reference" "R6P4"
			(at 0 0 0)
			(layer "B.SilkS")
			(hide yes)
			(effects
				(font
					(size 1.27 1.27)
				)
				(justify mirror)
			)
		)
		(property "Value" ""
			(at 0 0 0)
			(layer "B.Fab")
			(effects
				(font
					(size 1.27 1.27)
				)
				(justify mirror)
			)
		)
		(duplicate_pad_numbers_are_jumpers no)
		(fp_poly
			(pts
				(xy 0.2794 -0.1016) (xy -0.2794 -0.1016) (xy -0.2794 0.9906) (xy 0.2794 0.9906)
			)
			(stroke
				(width 0)
				(type default)
			)
			(fill no)
			(layer "B.CrtYd")
		)
		(fp_line
			(start -0.2794 -0.1016)
			(end 0.2794 -0.1016)
			(stroke
				(width 0.1)
				(type default)
			)
			(layer "B.Fab")
		)
		(fp_line
			(start -0.2794 0.9906)
			(end -0.2794 -0.1016)
			(stroke
				(width 0.1)
				(type default)
			)
			(layer "B.Fab")
		)
		(fp_line
			(start 0.2794 -0.1016)
			(end 0.2794 0.9906)
			(stroke
				(width 0.1)
				(type default)
			)
			(layer "B.Fab")
		)
		(fp_line
			(start 0.2794 0.9906)
			(end -0.2794 0.9906)
			(stroke
				(width 0.1)
				(type default)
			)
			(layer "B.Fab")
		)
		(pad "1" smd rect
			(at 0 0 180)
			(size 0.508 0.508)
			(layers "B.Cu" "B.Mask" "B.Paste")
			(net "CLK_100M_CPU0_RC_REFCLK1_DN")
		)
		(pad "2" smd rect
			(at 0 0.889 180)
			(size 0.508 0.508)
			(layers "B.Cu" "B.Mask" "B.Paste")
			(net "GND")
		)
		(zone
			(layer "B.Cu")
			(hatch none 0.5)
			(connect_pads
				(clearance 0)
			)
			(min_thickness 0.25)
			(keepout
				(tracks allowed)
				(vias not_allowed)
				(pads allowed)
				(copperpour not_allowed)
				(footprints allowed)
			)
			(placement
				(enabled no)
				(sheetname "")
			)
			(fill
				(thermal_gap 0.5)
				(thermal_bridge_width 0.5)
				(island_removal_mode 0)
			)
			(polygon
				(pts
					(xy 170.18 -87.503) (xy 169.672 -87.503) (xy 169.672 -87.122) (xy 170.18 -87.122)
				)
			)
		)
		(zone
			(layer "B.Cu")
			(hatch none 0.5)
			(connect_pads
				(clearance 0)
			)
			(min_thickness 0.25)
			(keepout
				(tracks not_allowed)
				(vias allowed)
				(pads allowed)
				(copperpour not_allowed)
				(footprints allowed)
			)
			(placement
				(enabled no)
				(sheetname "")
			)
			(fill
				(thermal_gap 0.5)
				(thermal_bridge_width 0.5)
				(island_removal_mode 0)
			)
			(polygon
				(pts
					(xy 170.18 -87.122) (xy 169.672 -87.122) (xy 169.672 -87.503) (xy 170.18 -87.503)
				)
			)
		)
	)
	(footprint ""
		(layer "B.Cu")
		(at 352.552 -104.267 180)
		(property "Reference" "C22W33"
			(at 0 0 0)
			(layer "B.SilkS")
			(hide yes)
			(effects
				(font
					(size 1.27 1.27)
				)
				(justify mirror)
			)
		)
		(property "Value" "*"
			(at 0.0762 -6.2357 180)
			(unlocked yes)
			(layer "B.Fab")
			(hide yes)
			(effects
				(font
					(size 1.27 1.016)
					(thickness 0.1524)
				)
				(justify mirror)
			)
		)
		(property "Device Type" "SC22U16V5MX-4-GP_SMD-BCG5-SC22A"
			(at 0.0762 -8.2677 180)
			(unlocked yes)
			(layer "B.Fab")
			(hide yes)
			(effects
				(font
					(size 1.27 1.016)
					(thickness 0.1524)
				)
				(justify mirror)
			)
		)
		(duplicate_pad_numbers_are_jumpers no)
		(fp_line
			(start -0.635 0)
			(end 0.635 0)
			(stroke
				(width 0.508)
				(type default)
			)
			(layer "B.SilkS")
		)
		(fp_rect
			(start 0.9652 1.778)
			(end -0.9652 -1.778)
			(stroke
				(width 0)
				(type default)
			)
			(fill no)
			(layer "B.CrtYd")
		)
		(fp_poly
			(pts
				(xy 0.9652 -1.778) (xy -0.9652 -1.778) (xy -0.9652 1.778) (xy 0.9652 1.778)
			)
			(stroke
				(width 0)
				(type default)
			)
			(fill no)
			(layer "B.Fab")
		)
		(pad "1" smd rect
			(at 0 -0.9652)
			(size 1.397 1.143)
			(layers "B.Cu" "B.Mask" "B.Paste")
			(net "VR_FET_SW_P12V_STBY_PVCCIO_CPU0")
		)
		(pad "2" smd rect
			(at 0 0.9652)
			(size 1.397 1.143)
			(layers "B.Cu" "B.Mask" "B.Paste")
			(net "GND")
		)
	)
)
